(kicad_pcb
	(version 20241229)
	(generator "pcbnew")
	(generator_version "9.0")
	(general
		(thickness 1.61)
		(legacy_teardrops no)
	)
	(paper "A3")
	(title_block
		(title "RDIMM DDR5 Tester")
		(date "2026-05-21")
		(rev "2.2.0")
		(company "Antmicro")
		(comment 9 "footprint 109 of 796 (J2), pads 174-259 of 291")
	)
	(layers
		(0 "F.Cu" signal)
		(4 "In1.Cu" power)
		(6 "In2.Cu" mixed)
		(8 "In3.Cu" power)
		(10 "In4.Cu" mixed)
		(12 "In5.Cu" power)
		(14 "In6.Cu" mixed)
		(16 "In7.Cu" power)
		(18 "In8.Cu" power)
		(20 "In9.Cu" mixed)
		(22 "In10.Cu" power)
		(2 "B.Cu" signal)
		(9 "F.Adhes" user "F.Adhesive")
		(11 "B.Adhes" user "B.Adhesive")
		(13 "F.Paste" user)
		(15 "B.Paste" user)
		(5 "F.SilkS" user "F.Silkscreen")
		(7 "B.SilkS" user "B.Silkscreen")
		(1 "F.Mask" user)
		(3 "B.Mask" user)
		(17 "Dwgs.User" user "User.Drawings")
		(19 "Cmts.User" user "User.Comments")
		(21 "Eco1.User" user "User.Eco1")
		(23 "Eco2.User" user "User.Eco2")
		(25 "Edge.Cuts" user)
		(27 "Margin" user)
		(31 "F.CrtYd" user "F.Courtyard")
		(29 "B.CrtYd" user "B.Courtyard")
		(35 "F.Fab" user)
		(33 "B.Fab" user)
	)
	(footprint "antmicro-footprints:Bus_DDR5_Socket_Amphenol_DDR504111002KQ"
		(layer "F.Cu")
		(at 188.325 108.297 180)
		(descr "DIMM Connectors DDR5 SMD 288P")
		(property "Reference" "J2"
			(at 67.825 3.797 0)
			(layer "F.SilkS")
			(effects
				(font
					(size 0.7 0.7)
					(thickness 0.15)
				)
				(justify right bottom)
			)
		)
		(property "Value" "Bus_DDR5_DDR504111002KQ"
			(at 0 4.2 0)
			(layer "F.Fab")
			(effects
				(font
					(size 0.7 0.7)
					(thickness 0.15)
				)
				(justify right bottom)
			)
		)
		(property "Datasheet" "https://www.amphenol-icc.com/ddr5-smt-ddr504111002kq.html"
			(at 0 0 180)
			(layer "F.Fab")
			(hide yes)
			(effects
				(font
					(size 1.27 1.27)
					(thickness 0.15)
				)
			)
		)
		(property "Manufacturer" "Amphenol"
			(at 0 0 180)
			(unlocked yes)
			(layer "F.Fab")
			(hide yes)
			(effects
				(font
					(size 1 1)
					(thickness 0.15)
				)
			)
		)
		(property "MPN" "DDR504111002KQ"
			(at 0 0 180)
			(unlocked yes)
			(layer "F.Fab")
			(hide yes)
			(effects
				(font
					(size 1 1)
					(thickness 0.15)
				)
			)
		)
		(property "Author" "Antmicro"
			(at 0 0 180)
			(unlocked yes)
			(layer "F.Fab")
			(hide yes)
			(effects
				(font
					(size 1 1)
					(thickness 0.15)
				)
			)
		)
		(property "License" "Apache-2.0"
			(at 0 0 180)
			(unlocked yes)
			(layer "F.Fab")
			(hide yes)
			(effects
				(font
					(size 1 1)
					(thickness 0.15)
				)
			)
		)
		(sheetname "/DDR5 RDIMM/")
		(sheetfile "ddr5-rdimm.kicad_sch")
		(attr smd)
		(pad "174" smd rect
			(at -38.676 -2.301 270)
			(size 1.8 0.57)
			(layers "F.Cu" "F.Mask" "F.Paste")
			(net 145 "/DDR5 RDIMM/A.DQ18")
			(pinfunction "DQ18_A")
			(pintype "input")
		)
		(pad "175" smd rect
			(at -37.826 -2.301 270)
			(size 1.8 0.57)
			(layers "F.Cu" "F.Mask" "F.Paste")
			(net 1 "GND")
			(pinfunction "VSS")
			(pintype "passive")
		)
		(pad "176" smd rect
			(at -36.976 -2.301 270)
			(size 1.8 0.57)
			(layers "F.Cu" "F.Mask" "F.Paste")
			(net 146 "/DDR5 RDIMM/A.DQ19")
			(pinfunction "DQ19_A")
			(pintype "input")
		)
		(pad "177" smd rect
			(at -36.125 -2.301 270)
			(size 1.8 0.57)
			(layers "F.Cu" "F.Mask" "F.Paste")
			(net 1 "GND")
			(pinfunction "VSS")
			(pintype "passive")
		)
		(pad "178" smd rect
			(at -35.275 -2.301 270)
			(size 1.8 0.57)
			(layers "F.Cu" "F.Mask" "F.Paste")
			(net 208 "/DDR5 RDIMM/A.DQS7_N")
			(pinfunction "DQS7_A_C")
			(pintype "input")
		)
		(pad "179" smd rect
			(at -34.426 -2.301 270)
			(size 1.8 0.57)
			(layers "F.Cu" "F.Mask" "F.Paste")
			(net 209 "/DDR5 RDIMM/A.DQS7_P")
			(pinfunction "DQS7_A_T")
			(pintype "input")
		)
		(pad "180" smd rect
			(at -33.576 -2.301 270)
			(size 1.8 0.57)
			(layers "F.Cu" "F.Mask" "F.Paste")
			(net 1 "GND")
			(pinfunction "VSS")
			(pintype "passive")
		)
		(pad "181" smd rect
			(at -32.726 -2.301 270)
			(size 1.8 0.57)
			(layers "F.Cu" "F.Mask" "F.Paste")
			(net 149 "/DDR5 RDIMM/A.DQ22")
			(pinfunction "DQ22_A")
			(pintype "input")
		)
		(pad "182" smd rect
			(at -31.875 -2.301 270)
			(size 1.8 0.57)
			(layers "F.Cu" "F.Mask" "F.Paste")
			(net 1 "GND")
			(pinfunction "VSS")
			(pintype "passive")
		)
		(pad "183" smd rect
			(at -31.026 -2.301 270)
			(size 1.8 0.57)
			(layers "F.Cu" "F.Mask" "F.Paste")
			(net 153 "/DDR5 RDIMM/A.DQ23")
			(pinfunction "DQ23_A")
			(pintype "input")
		)
		(pad "184" smd rect
			(at -30.177 -2.301 270)
			(size 1.8 0.57)
			(layers "F.Cu" "F.Mask" "F.Paste")
			(net 1 "GND")
			(pinfunction "VSS")
			(pintype "passive")
		)
		(pad "185" smd rect
			(at -29.325 -2.301 270)
			(size 1.8 0.57)
			(layers "F.Cu" "F.Mask" "F.Paste")
			(net 154 "/DDR5 RDIMM/A.DQ26")
			(pinfunction "DQ26_A")
			(pintype "input")
		)
		(pad "186" smd rect
			(at -28.476 -2.301 270)
			(size 1.8 0.57)
			(layers "F.Cu" "F.Mask" "F.Paste")
			(net 1 "GND")
			(pinfunction "VSS")
			(pintype "passive")
		)
		(pad "187" smd rect
			(at -27.625 -2.301 270)
			(size 1.8 0.57)
			(layers "F.Cu" "F.Mask" "F.Paste")
			(net 155 "/DDR5 RDIMM/A.DQ27")
			(pinfunction "DQ27_A")
			(pintype "input")
		)
		(pad "188" smd rect
			(at -26.776 -2.301 270)
			(size 1.8 0.57)
			(layers "F.Cu" "F.Mask" "F.Paste")
			(net 1 "GND")
			(pinfunction "VSS")
			(pintype "passive")
		)
		(pad "189" smd rect
			(at -25.927 -2.301 270)
			(size 1.8 0.57)
			(layers "F.Cu" "F.Mask" "F.Paste")
			(net 214 "/DDR5 RDIMM/A.DQS8_N")
			(pinfunction "DQS8_A_C")
			(pintype "input")
		)
		(pad "190" smd rect
			(at -25.075 -2.301 270)
			(size 1.8 0.57)
			(layers "F.Cu" "F.Mask" "F.Paste")
			(net 216 "/DDR5 RDIMM/A.DQS8_P")
			(pinfunction "DQS8_A_T")
			(pintype "input")
		)
		(pad "191" smd rect
			(at -24.226 -2.301 270)
			(size 1.8 0.57)
			(layers "F.Cu" "F.Mask" "F.Paste")
			(net 1 "GND")
			(pinfunction "VSS")
			(pintype "passive")
		)
		(pad "192" smd rect
			(at -23.375 -2.301 270)
			(size 1.8 0.57)
			(layers "F.Cu" "F.Mask" "F.Paste")
			(net 162 "/DDR5 RDIMM/A.DQ30")
			(pinfunction "DQ30_A")
			(pintype "input")
		)
		(pad "193" smd rect
			(at -22.526 -2.301 270)
			(size 1.8 0.57)
			(layers "F.Cu" "F.Mask" "F.Paste")
			(net 1 "GND")
			(pinfunction "VSS")
			(pintype "passive")
		)
		(pad "194" smd rect
			(at -21.677 -2.301 270)
			(size 1.8 0.57)
			(layers "F.Cu" "F.Mask" "F.Paste")
			(net 166 "/DDR5 RDIMM/A.DQ31")
			(pinfunction "DQ31_A")
			(pintype "input")
		)
		(pad "195" smd rect
			(at -20.825 -2.301 270)
			(size 1.8 0.57)
			(layers "F.Cu" "F.Mask" "F.Paste")
			(net 1 "GND")
			(pinfunction "VSS")
			(pintype "passive")
		)
		(pad "196" smd rect
			(at -19.976 -2.301 270)
			(size 1.8 0.57)
			(layers "F.Cu" "F.Mask" "F.Paste")
			(net 171 "/DDR5 RDIMM/A.CB2")
			(pinfunction "CB2_A")
			(pintype "input")
		)
		(pad "197" smd rect
			(at -19.125 -2.301 270)
			(size 1.8 0.57)
			(layers "F.Cu" "F.Mask" "F.Paste")
			(net 1 "GND")
			(pinfunction "VSS")
			(pintype "passive")
		)
		(pad "198" smd rect
			(at -18.276 -2.301 270)
			(size 1.8 0.57)
			(layers "F.Cu" "F.Mask" "F.Paste")
			(net 173 "/DDR5 RDIMM/A.CB3")
			(pinfunction "CB3_A")
			(pintype "input")
		)
		(pad "199" smd rect
			(at -17.427 -2.301 270)
			(size 1.8 0.57)
			(layers "F.Cu" "F.Mask" "F.Paste")
			(net 1 "GND")
			(pinfunction "VSS")
			(pintype "passive")
		)
		(pad "200" smd rect
			(at -16.575 -2.301 270)
			(size 1.8 0.57)
			(layers "F.Cu" "F.Mask" "F.Paste")
			(net 234 "/DDR5 RDIMM/A.DQS9_N")
			(pinfunction "DQS9_A_C")
			(pintype "input")
		)
		(pad "201" smd rect
			(at -15.725 -2.301 270)
			(size 1.8 0.57)
			(layers "F.Cu" "F.Mask" "F.Paste")
			(net 235 "/DDR5 RDIMM/A.DQS9_P")
			(pinfunction "DQS9_A_T")
			(pintype "input")
		)
		(pad "202" smd rect
			(at -14.875 -2.301 270)
			(size 1.8 0.57)
			(layers "F.Cu" "F.Mask" "F.Paste")
			(net 1 "GND")
			(pinfunction "VSS")
			(pintype "passive")
		)
		(pad "203" smd rect
			(at -14.026 -2.301 270)
			(size 1.8 0.57)
			(layers "F.Cu" "F.Mask" "F.Paste")
			(net 186 "/DDR5 RDIMM/A.CB6")
			(pinfunction "CB6_A")
			(pintype "input")
		)
		(pad "204" smd rect
			(at -13.176 -2.301 270)
			(size 1.8 0.57)
			(layers "F.Cu" "F.Mask" "F.Paste")
			(net 1 "GND")
			(pinfunction "VSS")
			(pintype "passive")
		)
		(pad "205" smd rect
			(at -12.326 -2.301 270)
			(size 1.8 0.57)
			(layers "F.Cu" "F.Mask" "F.Paste")
			(net 187 "/DDR5 RDIMM/A.CB7")
			(pinfunction "CB7_A")
			(pintype "input")
		)
		(pad "206" smd rect
			(at -11.475 -2.301 270)
			(size 1.8 0.57)
			(layers "F.Cu" "F.Mask" "F.Paste")
			(net 1 "GND")
			(pinfunction "VSS")
			(pintype "passive")
		)
		(pad "207" smd rect
			(at -10.625 -2.301 270)
			(size 1.8 0.57)
			(layers "F.Cu" "F.Mask" "F.Paste")
			(net 190 "/DDR5 RDIMM/CTRL.~{RESET}")
			(pinfunction "RESET_N")
			(pintype "input")
		)
		(pad "208" smd rect
			(at -9.776 -2.301 270)
			(size 1.8 0.57)
			(layers "F.Cu" "F.Mask" "F.Paste")
			(net 1 "GND")
			(pinfunction "VSS")
			(pintype "passive")
		)
		(pad "209" smd rect
			(at -8.926 -2.301 270)
			(size 1.8 0.57)
			(layers "F.Cu" "F.Mask" "F.Paste")
			(net 191 "/DDR5 RDIMM/A.CS1_c")
			(pinfunction "CS1_A_N")
			(pintype "input")
		)
		(pad "210" smd rect
			(at -8.075 -2.301 270)
			(size 1.8 0.57)
			(layers "F.Cu" "F.Mask" "F.Paste")
			(net 1 "GND")
			(pinfunction "VSS")
			(pintype "passive")
		)
		(pad "211" smd rect
			(at -7.226 -2.301 270)
			(size 1.8 0.57)
			(layers "F.Cu" "F.Mask" "F.Paste")
			(net 192 "/DDR5 RDIMM/A.CA1")
			(pinfunction "CA1_A")
			(pintype "input")
		)
		(pad "212" smd rect
			(at -6.375 -2.301 270)
			(size 1.8 0.57)
			(layers "F.Cu" "F.Mask" "F.Paste")
			(net 1 "GND")
			(pinfunction "VSS")
			(pintype "passive")
		)
		(pad "213" smd rect
			(at -5.526 -2.301 270)
			(size 1.8 0.57)
			(layers "F.Cu" "F.Mask" "F.Paste")
			(net 193 "/DDR5 RDIMM/A.CA3")
			(pinfunction "CA3_A")
			(pintype "input")
		)
		(pad "214" smd rect
			(at -4.675 -2.301 270)
			(size 1.8 0.57)
			(layers "F.Cu" "F.Mask" "F.Paste")
			(net 1 "GND")
			(pinfunction "VSS")
			(pintype "passive")
		)
		(pad "215" smd rect
			(at -3.826 -2.301 270)
			(size 1.8 0.57)
			(layers "F.Cu" "F.Mask" "F.Paste")
			(net 194 "/DDR5 RDIMM/A.CA5")
			(pinfunction "CA5_A")
			(pintype "input")
		)
		(pad "216" smd rect
			(at -2.976 -2.301 270)
			(size 1.8 0.57)
			(layers "F.Cu" "F.Mask" "F.Paste")
			(net 1 "GND")
			(pinfunction "VSS")
			(pintype "passive")
		)
		(pad "217" smd rect
			(at -2.125 -2.301 270)
			(size 1.8 0.57)
			(layers "F.Cu" "F.Mask" "F.Paste")
			(net 634 "/DDR5 RDIMM/CTRL.CK_P")
			(pinfunction "CK_T")
			(pintype "input")
		)
		(pad "218" smd rect
			(at -1.276 -2.301 270)
			(size 1.8 0.57)
			(layers "F.Cu" "F.Mask" "F.Paste")
			(net 633 "/DDR5 RDIMM/CTRL.CK_N")
			(pinfunction "CK_C")
			(pintype "input")
		)
		(pad "219" smd rect
			(at -0.425 -2.301 270)
			(size 1.8 0.57)
			(layers "F.Cu" "F.Mask" "F.Paste")
			(net 1 "GND")
			(pinfunction "VSS")
			(pintype "passive")
		)
		(pad "220" smd rect
			(at 5.525 -2.301 270)
			(size 1.8 0.57)
			(layers "F.Cu" "F.Mask" "F.Paste")
			(net 362 "unconnected-(J2B-RFU-Pad220)")
			(pinfunction "RFU")
			(pintype "no_connect")
		)
		(pad "221" smd rect
			(at 6.373 -2.301 270)
			(size 1.8 0.57)
			(layers "F.Cu" "F.Mask" "F.Paste")
			(net 198 "/DDR5 RDIMM/B.CA2")
			(pinfunction "CA1_B")
			(pintype "input")
		)
		(pad "222" smd rect
			(at 7.224 -2.301 270)
			(size 1.8 0.57)
			(layers "F.Cu" "F.Mask" "F.Paste")
			(net 1 "GND")
			(pinfunction "VSS")
			(pintype "passive")
		)
		(pad "223" smd rect
			(at 8.073 -2.301 270)
			(size 1.8 0.57)
			(layers "F.Cu" "F.Mask" "F.Paste")
			(net 199 "/DDR5 RDIMM/B.CA3")
			(pinfunction "CA3_B")
			(pintype "input")
		)
		(pad "224" smd rect
			(at 8.925 -2.301 270)
			(size 1.8 0.57)
			(layers "F.Cu" "F.Mask" "F.Paste")
			(net 1 "GND")
			(pinfunction "VSS")
			(pintype "passive")
		)
		(pad "225" smd rect
			(at 9.775 -2.301 270)
			(size 1.8 0.57)
			(layers "F.Cu" "F.Mask" "F.Paste")
			(net 200 "/DDR5 RDIMM/B.CA5")
			(pinfunction "CA5_B")
			(pintype "input")
		)
		(pad "226" smd rect
			(at 10.624 -2.301 270)
			(size 1.8 0.57)
			(layers "F.Cu" "F.Mask" "F.Paste")
			(net 1 "GND")
			(pinfunction "VSS")
			(pintype "passive")
		)
		(pad "227" smd rect
			(at 11.473 -2.301 270)
			(size 1.8 0.57)
			(layers "F.Cu" "F.Mask" "F.Paste")
			(net 202 "/DDR5 RDIMM/B.PAR")
			(pinfunction "PAR_B")
			(pintype "input")
		)
		(pad "228" smd rect
			(at 12.323 -2.301 270)
			(size 1.8 0.57)
			(layers "F.Cu" "F.Mask" "F.Paste")
			(net 1 "GND")
			(pinfunction "VSS")
			(pintype "passive")
		)
		(pad "229" smd rect
			(at 13.175 -2.301 270)
			(size 1.8 0.57)
			(layers "F.Cu" "F.Mask" "F.Paste")
			(net 203 "/DDR5 RDIMM/B.CS1_c")
			(pinfunction "CS1_B_N")
			(pintype "input")
		)
		(pad "230" smd rect
			(at 14.025 -2.301 270)
			(size 1.8 0.57)
			(layers "F.Cu" "F.Mask" "F.Paste")
			(net 1 "GND")
			(pinfunction "VSS")
			(pintype "passive")
		)
		(pad "231" smd rect
			(at 14.874 -2.301 270)
			(size 1.8 0.57)
			(layers "F.Cu" "F.Mask" "F.Paste")
			(net 195 "unconnected-(J2B-RFU-Pad231)")
			(pinfunction "RFU")
			(pintype "no_connect")
		)
		(pad "232" smd rect
			(at 15.723 -2.301 270)
			(size 1.8 0.57)
			(layers "F.Cu" "F.Mask" "F.Paste")
			(net 196 "unconnected-(J2B-RFU-Pad232)")
			(pinfunction "RFU")
			(pintype "no_connect")
		)
		(pad "233" smd rect
			(at 16.574 -2.301 270)
			(size 1.8 0.57)
			(layers "F.Cu" "F.Mask" "F.Paste")
			(net 1 "GND")
			(pinfunction "VSS")
			(pintype "passive")
		)
		(pad "234" smd rect
			(at 17.425 -2.301 270)
			(size 1.8 0.57)
			(layers "F.Cu" "F.Mask" "F.Paste")
			(net 204 "/DDR5 RDIMM/B.CB6")
			(pinfunction "CB6_B")
			(pintype "input")
		)
		(pad "235" smd rect
			(at 18.274 -2.301 270)
			(size 1.8 0.57)
			(layers "F.Cu" "F.Mask" "F.Paste")
			(net 1 "GND")
			(pinfunction "VSS")
			(pintype "passive")
		)
		(pad "236" smd rect
			(at 19.123 -2.301 270)
			(size 1.8 0.57)
			(layers "F.Cu" "F.Mask" "F.Paste")
			(net 205 "/DDR5 RDIMM/B.CB7")
			(pinfunction "CB7_B")
			(pintype "input")
		)
		(pad "237" smd rect
			(at 19.975 -2.301 270)
			(size 1.8 0.57)
			(layers "F.Cu" "F.Mask" "F.Paste")
			(net 1 "GND")
			(pinfunction "VSS")
			(pintype "passive")
		)
		(pad "238" smd rect
			(at 20.824 -2.301 270)
			(size 1.8 0.57)
			(layers "F.Cu" "F.Mask" "F.Paste")
			(net 451 "/DDR5 RDIMM/B.DQS4_N")
			(pinfunction "DQS4_B_C")
			(pintype "input")
		)
		(pad "239" smd rect
			(at 21.675 -2.301 270)
			(size 1.8 0.57)
			(layers "F.Cu" "F.Mask" "F.Paste")
			(net 452 "/DDR5 RDIMM/B.DQS4_P")
			(pinfunction "DQS4_B_T")
			(pintype "input")
		)
		(pad "240" smd rect
			(at 22.524 -2.301 270)
			(size 1.8 0.57)
			(layers "F.Cu" "F.Mask" "F.Paste")
			(net 1 "GND")
			(pinfunction "VSS")
			(pintype "passive")
		)
		(pad "241" smd rect
			(at 23.373 -2.301 270)
			(size 1.8 0.57)
			(layers "F.Cu" "F.Mask" "F.Paste")
			(net 210 "/DDR5 RDIMM/B.CB2")
			(pinfunction "CB2_B")
			(pintype "input")
		)
		(pad "242" smd rect
			(at 24.225 -2.301 270)
			(size 1.8 0.57)
			(layers "F.Cu" "F.Mask" "F.Paste")
			(net 1 "GND")
			(pinfunction "VSS")
			(pintype "passive")
		)
		(pad "243" smd rect
			(at 25.074 -2.301 270)
			(size 1.8 0.57)
			(layers "F.Cu" "F.Mask" "F.Paste")
			(net 211 "/DDR5 RDIMM/B.CB3")
			(pinfunction "CB3_B")
			(pintype "input")
		)
		(pad "244" smd rect
			(at 25.925 -2.301 270)
			(size 1.8 0.57)
			(layers "F.Cu" "F.Mask" "F.Paste")
			(net 1 "GND")
			(pinfunction "VSS")
			(pintype "passive")
		)
		(pad "245" smd rect
			(at 26.774 -2.301 270)
			(size 1.8 0.57)
			(layers "F.Cu" "F.Mask" "F.Paste")
			(net 212 "/DDR5 RDIMM/B.DQ2")
			(pinfunction "DQ2_B")
			(pintype "input")
		)
		(pad "246" smd rect
			(at 27.623 -2.301 270)
			(size 1.8 0.57)
			(layers "F.Cu" "F.Mask" "F.Paste")
			(net 1 "GND")
			(pinfunction "VSS")
			(pintype "passive")
		)
		(pad "247" smd rect
			(at 28.475 -2.301 270)
			(size 1.8 0.57)
			(layers "F.Cu" "F.Mask" "F.Paste")
			(net 213 "/DDR5 RDIMM/B.DQ3")
			(pinfunction "DQ3_B")
			(pintype "input")
		)
		(pad "248" smd rect
			(at 29.324 -2.301 270)
			(size 1.8 0.57)
			(layers "F.Cu" "F.Mask" "F.Paste")
			(net 1 "GND")
			(pinfunction "VSS")
			(pintype "passive")
		)
		(pad "249" smd rect
			(at 30.175 -2.301 270)
			(size 1.8 0.57)
			(layers "F.Cu" "F.Mask" "F.Paste")
			(net 457 "/DDR5 RDIMM/B.DQS5_N")
			(pinfunction "DQS5_B_C")
			(pintype "input")
		)
		(pad "250" smd rect
			(at 31.024 -2.301 270)
			(size 1.8 0.57)
			(layers "F.Cu" "F.Mask" "F.Paste")
			(net 474 "/DDR5 RDIMM/B.DQS5_P")
			(pinfunction "DQS5_B_T")
			(pintype "input")
		)
		(pad "251" smd rect
			(at 31.873 -2.301 270)
			(size 1.8 0.57)
			(layers "F.Cu" "F.Mask" "F.Paste")
			(net 1 "GND")
			(pinfunction "VSS")
			(pintype "passive")
		)
		(pad "252" smd rect
			(at 32.725 -2.301 270)
			(size 1.8 0.57)
			(layers "F.Cu" "F.Mask" "F.Paste")
			(net 217 "/DDR5 RDIMM/B.DQ6")
			(pinfunction "DQ6_B")
			(pintype "input")
		)
		(pad "253" smd rect
			(at 33.575 -2.301 270)
			(size 1.8 0.57)
			(layers "F.Cu" "F.Mask" "F.Paste")
			(net 1 "GND")
			(pinfunction "VSS")
			(pintype "passive")
		)
		(pad "254" smd rect
			(at 34.423 -2.301 270)
			(size 1.8 0.57)
			(layers "F.Cu" "F.Mask" "F.Paste")
			(net 218 "/DDR5 RDIMM/B.DQ7")
			(pinfunction "DQ7_B")
			(pintype "input")
		)
		(pad "255" smd rect
			(at 35.274 -2.301 270)
			(size 1.8 0.57)
			(layers "F.Cu" "F.Mask" "F.Paste")
			(net 1 "GND")
			(pinfunction "VSS")
			(pintype "passive")
		)
		(pad "256" smd rect
			(at 36.124 -2.301 270)
			(size 1.8 0.57)
			(layers "F.Cu" "F.Mask" "F.Paste")
			(net 219 "/DDR5 RDIMM/B.DQ10")
			(pinfunction "DQ10_B")
			(pintype "input")
		)
		(pad "257" smd rect
			(at 36.975 -2.301 270)
			(size 1.8 0.57)
			(layers "F.Cu" "F.Mask" "F.Paste")
			(net 1 "GND")
			(pinfunction "VSS")
			(pintype "passive")
		)
		(pad "258" smd rect
			(at 37.825 -2.301 270)
			(size 1.8 0.57)
			(layers "F.Cu" "F.Mask" "F.Paste")
			(net 229 "/DDR5 RDIMM/B.DQ11")
			(pinfunction "DQ11_B")
			(pintype "input")
		)
		(pad "259" smd rect
			(at 38.673 -2.301 270)
			(size 1.8 0.57)
			(layers "F.Cu" "F.Mask" "F.Paste")
			(net 1 "GND")
			(pinfunction "VSS")
			(pintype "passive")
		)
	)
)
